FILE_TYPE = CONNECTIVITY;
{Allegro Design Entry HDL 16.6-p007 (v16-6-112F) 10/10/2012}
"PAGE_NUMBER" = 102;
0"NC";
1"P3V3_DB1200\g";
2"P3V3_DB1200\g";
3"P3V3_DB1200\g";
4"GND\g";
5"GND\g";
6"GND\g";
7"P3V3_DB1200\g";
8"P3V3_DB1200\g";
9"P3V3_DB1200\g";
10"P3V3_DB1200\g";
11"GND\g";
12"P3V3_DB1200\g";
13"GND\g";
14"P3V3_DB1200\g";
15"GND\g";
16"GND\g";
17"P3V3\g";
18"P3V3\g";
19"P3V3_DB1200_A"VOLTAGE"+3.3V";
20"FM_DB1200ZL_BCLKS_EN_N";
21"FM_CPU1_MCP_CLK_EN_N";
22"FM_100M_N";
23"FM_HBW_BYPASS_LOWBW_N";
24"CLK_100M_CPU0_BCLK0_R_DN";
25"CLK_100M_CPU0_BCLK0_R_DP";
26"CLK_100M_CPU1_RC_REFCLK1_R_DN";
27"FM_CPU1_MCP_CLK_EN_N";
28"FM_DB1200_PWRGD_R";
29"CLK_100M_DB1200_DP";
30"CLK_100M_DB1200_DN";
31"FM_DB1200_PWRGD";
32"SMB_HOST_STBY_LVC3_SCL_R2";
33"FM_DB1200ZL_BCLKS_EN_N";
34"FM_CPU0_MCP_CLK_EN_N";
35"FM_DB1200_SMB_SA0";
36"FM_DB1200_SMB_SA1";
37"SMB_HOST_STBY_LVC3_SDA_R2";
38"P3V3_DB1200_R"VOLTAGE"+3.3V";
39"CLK_100M_CPU0_BCLK2_R_DN";
40"CLK_100M_CPU0_BCLK2_R_DP";
41"CLK_100M_CPU0_PE_REFCLK_R_DN";
42"CLK_100M_CPU0_BCLK1_R_DN";
43"CLK_100M_CPU0_PE_REFCLK_R_DP";
44"CLK_100M_CPU0_RC_REFCLK0_R_DP";
45"CLK_100M_CPU1_BCLK0_R_DN";
46"FM_DB1200_SMB_SA0";
47"P3V3_DB1200_R1";
48"SMB_HOST_STBY_LVC3_SDA_R2";
49"SMB_HOST_STBY_LVC3_SDA";
50"SMB_HOST_STBY_LVC3_SCL";
51"CLK_100M_CPU0_RC_REFCLK1_R_DP";
52"FM_HBW_BYPASS_LOWBW_N";
53"FM_100M_N";
54"FM_CPU0_MCP_CLK_EN_N";
55"CLK_100M_CPU0_BCLK1_R_DP";
56"CLK_100M_CPU1_BCLK1_R_DN";
57"CLK_100M_CPU1_BCLK2_R_DN";
58"CLK_100M_CPU1_BCLK1_R_DP";
59"CLK_100M_CPU1_PE_REFCLK_R_DN";
60"CLK_100M_CPU1_BCLK2_R_DP";
61"CLK_100M_CPU1_PE_REFCLK_R_DP";
62"CLK_100M_CPU1_RC_REFCLK0_R_DN";
63"CLK_100M_CPU1_RC_REFCLK1_R_DP";
64"CLK_100M_CPU1_RC_REFCLK0_R_DP";
65"CLK_100M_CPU0_RC_REFCLK0_R_DN";
66"CLK_100M_CPU1_BCLK0_R_DP";
67"CLK_100M_CPU0_RC_REFCLK1_R_DN";
68"FM_DB1200_SMB_SA1";
69"SMB_HOST_STBY_LVC3_SCL_R2";
%"NB3W1200L"
"1","(350,2900)","0","mstr_clock","I1";
;
CDS_SEC"1"
PART_NUMBER"H13585-001"
MATERIAL"IC"
LOCATION"EU4D2"
CDS_LMAN_SYM_OUTLINE"-600,1000,600,-1000"
CDS_LIB"mstr_clock"
PACK_TYPE"LCC"
BOM_COST"SYS_CLOCK"
SEC_TYPE"LCC"
SEC"1"
ROOM"DB1200ZL"
CDS_LOCATION"EU4D2";
"SCL"
$PN"13"32;
"100M_133M_N"
$PN"4"22;
"OE_2_N"
$PN"28"33;
"OE_1_N"
$PN"20"33;
"OE_0_N"
$PN"19"33;
"OE_3_N"
$PN"29"34;
"OE_4_N"
$PN"36"34;
"OE_5_N"
$PN"37"34;
"OE_6_N"
$PN"44"33;
"OE_7_N"
$PN"45"33;
"VDDIO<1>"
$PN"32"9;
"VDDIO<2>"
$PN"49"9;
"VDDIO<0>"
$PN"25"9;
"VDDIO<3>"
$PN"56"9;
"OE_8_N"
$PN"52"33;
"OE_11_N"
$PN"62"27;
"OE_10_N"
$PN"61"27;
"OE_9_N"
$PN"53"27;
"VDD<2>"
$PN"57"9;
"VDD<1>"
$PN"40"9;
"VDDR"
$PN"8"38;
"VDD<0>"
$PN"24"9;
"VDDA"
$PN"1"19;
"GND<2>"
$PN"33"16;
"GND<4>"
$PN"48"16;
"GND<3>"
$PN"41"16;
"GND<5>"
$PN"58"16;
"THPAD"
$PN"65"16;
"GND<0>"
$PN"7"16;
"GND<1>"
$PN"23"16;
"GNDA"
$PN"2"16;
"DIF_2N"
$PN"27"39;
"DIF_1P"
$PN"21"55;
"DIF_1N"
$PN"22"42;
"DIF_0P"
$PN"17"25;
"DIF_0N"
$PN"18"24;
"DIF_2P"
$PN"26"40;
"DIF_6N"
$PN"43"45;
"DIF_5P"
$PN"38"51;
"DIF_3P"
$PN"30"43;
"DIF_4P"
$PN"34"44;
"DIF_4N"
$PN"35"65;
"DIF_5N"
$PN"39"67;
"DIF_3N"
$PN"31"41;
"DIF_6P"
$PN"42"66;
"DIF_7N"
$PN"47"56;
"DIF_7P"
$PN"46"58;
"DIF_11N"
$PN"64"26;
"DIF_11P"
$PN"63"63;
"DIF_10N"
$PN"60"62;
"DIF_9P"
$PN"54"61;
"DIF_10P"
$PN"59"64;
"DIF_9N"
$PN"55"59;
"DIF_8P"
$PN"50"60;
"DIF_8N"
$PN"51"57;
"CLK_INN"
$PN"10"30;
"CLK_INP"
$PN"9"29;
"HBW_BYPASS_LOBW_N \B"
$PN"5"23;
"PWRGD_PWRDN_N \B"
$PN"6"28;
"SA_0"
$PN"11"46;
"SA_1"
$PN"14"68;
"SDA"
$PN"12"37;
"NC<0>"
$PN"3"0;
"NC<2>"
$PN"15"0;
"NC<1>"
$PN"16"0;
%"CAP"
"1","(1975,900)","0","mstr_discrete","I10";
;
CDS_SEC"1"
LOCATION"C3D22"
PART_NUMBER"G10601-001"
VALUE"10UF"
TOLERANCE"10%"
PACK_TYPE"0805"
VOLTAGE"16V"
MATERIAL"X7R"
BOM_COST"SYS_CLOCK"
SEC_TYPE"0805"
SEC"1"
CDS_LOCATION"C3D22"
ROOM"DB1200ZL"
CDS_LIB"mstr_discrete";
"A"
$PN"1"7;
"B"
$PN"2"5;
%"FET_N_DUAL"
"5","(2000,4100)","3","mstr_discrete","I101";
;
VALUE"2N7002DW"
MATERIAL"FET"
PART_NUMBER"D24280-001"
LOCATION"Q4W1"
CDS_SEC"2"
BOM_COST"DEBUG"
ROOM"UART_MUX"
CDS_LIB"mstr_discrete"
PACK_TYPE"SMLF"
SEC"2"
SEC_TYPE"SMLF"
CDS_LOCATION"Q4W1";
"GATE <SIZE -1..0>"
$PN"5"47;
"SOURCE <SIZE-1..0>"
$PN"4"69;
"DRAIN <SIZE -1..0>"
$PN"3"50;
%"FET_N_DUAL"
"5","(2350,4500)","3","mstr_discrete","I102";
;
PART_NUMBER"D24280-001"
MATERIAL"FET"
VALUE"2N7002DW"
LOCATION"Q4W1"
ROOM"UART_MUX"
BOM_COST"DEBUG"
CDS_LIB"mstr_discrete"
PACK_TYPE"SMLF"
SEC"1"
SEC_TYPE"SMLF"
CDS_SEC"1"
CDS_LOCATION"Q4W1";
"GATE <SIZE -1..0>"
$PN"2"47;
"SOURCE <SIZE-1..0>"
$PN"1"48;
"DRAIN <SIZE -1..0>"
$PN"6"49;
%"RES"
"2","(2450,4900)","0","mstr_discrete","I103";
;
CDS_SEC"1"
LOCATION"R4W2"
VALUE"1.00K"
PART_NUMBER"G21796-026"
MATERIAL"CHIP"
WATTAGE"1/16W"
PACK_TYPE"0402"
TOLERANCE"1%"
CDS_LIB"mstr_discrete"
SEC"1"
SEC_TYPE"0402"
ROOM"PROC_SIDEBAND"
CDS_LOCATION"R4W2";
"A"
$PN"1"1;
"B"
$PN"2"47;
%"VCC_CORE"
"1","(2450,5100)","0","mstr_symbols","I104";
;
HDL_POWER"P3V3_DB1200"
CDS_LIB"mstr_symbols"
VOLTAGE"5";
"A"1;
%"RES"
"1","(3300,4750)","5","mstr_discrete","I105";
;
CDS_SEC"1"
CDS_LOCATION"R4W3"
TOLERANCE"5%"
VALUE"3.3K"
WATTAGE"1/16W"
MATERIAL"CHIP"
LOCATION"R4W3"
PART_NUMBER"G21497-013"
PACK_TYPE"0402"
SEC"1"
SEC_TYPE"0402"
CDS_LIB"mstr_discrete";
"B"
$PN"2"48;
"A"
$PN"1"2;
%"RES"
"1","(3650,4750)","5","mstr_discrete","I106";
;
CDS_SEC"1"
CDS_LOCATION"R4W4"
TOLERANCE"5%"
WATTAGE"1/16W"
MATERIAL"CHIP"
VALUE"3.3K"
LOCATION"R4W4"
PART_NUMBER"G21497-013"
PACK_TYPE"0402"
SEC"1"
SEC_TYPE"0402"
CDS_LIB"mstr_discrete";
"B"
$PN"2"69;
"A"
$PN"1"2;
%"VCC_CORE"
"1","(3650,5100)","0","mstr_symbols","I107";
;
HDL_POWER"P3V3_DB1200"
VOLTAGE"5"
CDS_LIB"mstr_symbols";
"A"2;
%"RES"
"2","(-2400,2350)","0","mstr_discrete","I109";
;
CDS_SEC"1"
VALUE"4.75K"
TOLERANCE"1%"
WATTAGE"1/16W"
LOCATION"R4W6"
PACK_TYPE"0402"
PART_NUMBER"G21796-072"
MATERIAL"CHIP"
CDS_LIB"mstr_discrete"
ROOM"DB1200ZL"
SEC"1"
BOM_COST"SYS_CLOCK"
SEC_TYPE"0402"
CDS_LOCATION"R4W6";
"A"
$PN"1"3;
"B"
$PN"2"28;
%"CAP_A"
"1","(2575,900)","0","dev_discrete","I11";
;
LOCATION"C6P4"
PART_NUMBER"A36096-030"
MATERIAL"X7R"
PACK_TYPE"0402V"
TOLERANCE"10%"
VOLTAGE"16V"
VALUE"0.1UF"
BOM_COST"SYS_CLOCK"
SEC"1"
SEC_TYPE"0402V"
ROOM"DB1200ZL"
CDS_SEC"1"
CDS_LOCATION"C6P4"
CDS_LIB"dev_discrete";
"B"
$PN"2"5;
"A"
$PN"1"7;
%"VCC_CORE"
"1","(-2400,2550)","0","mstr_symbols","I110";
;
HDL_POWER"P3V3_DB1200"
VOLTAGE"5"
CDS_LIB"mstr_symbols";
"A"3;
%"FET_N"
"8","(-950,1950)","0","mstr_discrete","I112";
;
CDS_SEC"1"
VALUE"2N7002"
PART_NUMBER"C79254-001"
LOCATION"Q4W2"
MATERIAL"FET"
PACK_TYPE"SOT23LF"
ROOM"HOT_SWAP"
SEC_TYPE"SOT23LF"
SEC"1"
CDS_LIB"mstr_discrete"
CDS_LOCATION"Q4W2";
"GATE"
$PN"1"31;
"DRN"
$PN"3"28;
"SRC"
$PN"2"4;
%"GND"
"1","(-950,1650)","0","mstr_symbols","I113";
;
ROOM"DB1200ZL"
BOM_COST"SYS_CLOCK"
VOLTAGE"0.0V"
CDS_LIB"mstr_symbols"
SIZE"1B"
BODY_TYPE"PLUMBING"
HDL_POWER"GND";
"A\NAC"4;
%"RES"
"1","(-1650,2000)","1","mstr_discrete","I114";
;
CDS_SEC"1"
LOCATION"R4W5"
TOLERANCE"5%"
VALUE"0.0"
PART_NUMBER"G21497-005"
MATERIAL"EMPTY"
WATTAGE"1/16W"
PACK_TYPE"0402"
SEC"1"
SEC_TYPE"0402"
BOM_COST"MEM_NV"
ROOM"NV_DIMM"
CDS_LIB"mstr_discrete"
CDS_LOCATION"R4W5";
"B"
$PN"2"28;
"A"
$PN"1"31;
%"RES"
"2","(-750,1075)","0","mstr_discrete","I115";
;
CDS_SEC"1"
TOLERANCE"1%"
PACK_TYPE"0402"
LOCATION"R6P48"
VALUE"1.00K"
PART_NUMBER"G21796-026"
MATERIAL"CHIP"
WATTAGE"1/16W"
CDS_LIB"mstr_discrete"
SEC"1"
SEC_TYPE"0402"
ROOM"PROC_SIDEBAND"
CDS_LOCATION"R6P48";
"A"
$PN"1"18;
"B"
$PN"2"20;
%"CAP_A"
"1","(2825,900)","0","dev_discrete","I12";
;
PART_NUMBER"A36096-030"
LOCATION"C6P6"
MATERIAL"X7R"
VOLTAGE"16V"
PACK_TYPE"0402V"
TOLERANCE"10%"
VALUE"0.1UF"
BOM_COST"SYS_CLOCK"
ROOM"DB1200ZL"
CDS_LOCATION"C6P6"
CDS_SEC"1"
SEC_TYPE"0402V"
SEC"1"
CDS_LIB"dev_discrete";
"B"
$PN"2"5;
"A"
$PN"1"7;
%"CAP_A"
"1","(3050,900)","0","dev_discrete","I13";
;
LOCATION"C6P10"
PART_NUMBER"A36096-030"
MATERIAL"X7R"
VOLTAGE"16V"
PACK_TYPE"0402V"
TOLERANCE"10%"
VALUE"0.1UF"
BOM_COST"SYS_CLOCK"
SEC_TYPE"0402V"
ROOM"DB1200ZL"
CDS_LOCATION"C6P10"
CDS_SEC"1"
SEC"1"
CDS_LIB"dev_discrete";
"B"
$PN"2"5;
"A"
$PN"1"7;
%"CAP_A"
"1","(3275,900)","0","dev_discrete","I14";
;
PACK_TYPE"0402V"
VOLTAGE"16V"
MATERIAL"X7R"
TOLERANCE"10%"
PART_NUMBER"A36096-030"
VALUE"0.1UF"
LOCATION"C6P5"
BOM_COST"SYS_CLOCK"
SEC"1"
SEC_TYPE"0402V"
ROOM"DB1200ZL"
CDS_SEC"1"
CDS_LOCATION"C6P5"
CDS_LIB"dev_discrete";
"B"
$PN"2"5;
"A"
$PN"1"7;
%"CAP_A"
"1","(3475,900)","0","dev_discrete","I15";
;
VALUE"0.1UF"
PART_NUMBER"A36096-030"
TOLERANCE"10%"
PACK_TYPE"0402V"
VOLTAGE"16V"
MATERIAL"X7R"
LOCATION"C6P12"
BOM_COST"SYS_CLOCK"
SEC"1"
SEC_TYPE"0402V"
ROOM"DB1200ZL"
CDS_SEC"1"
CDS_LOCATION"C6P12"
CDS_LIB"dev_discrete";
"B"
$PN"2"5;
"A"
$PN"1"7;
%"CAP_A"
"1","(3700,900)","0","dev_discrete","I16";
;
LOCATION"C6P11"
PART_NUMBER"A36096-030"
PACK_TYPE"0402V"
TOLERANCE"10%"
MATERIAL"X7R"
VALUE"0.1UF"
VOLTAGE"16V"
BOM_COST"SYS_CLOCK"
CDS_SEC"1"
SEC_TYPE"0402V"
SEC"1"
CDS_LOCATION"C6P11"
ROOM"DB1200ZL"
CDS_LIB"dev_discrete";
"B"
$PN"2"5;
"A"
$PN"1"7;
%"GND"
"1","(3700,550)","0","mstr_symbols","I17";
;
SIZE"1B"
VOLTAGE"0.0V"
CDS_LIB"mstr_symbols"
ROOM"DB1200ZL"
BOM_COST"SYS_CLOCK"
BODY_TYPE"PLUMBING"
HDL_POWER"GND";
"A\NAC"5;
%"CAP_A"
"1","(-1550,3900)","0","dev_discrete","I18";
;
TOLERANCE"10%"
VALUE"0.1UF"
MATERIAL"X7R"
LOCATION"C4D24"
PART_NUMBER"A36096-030"
VOLTAGE"16V"
PACK_TYPE"0402V"
ROOM"DB1200ZL"
BOM_COST"SYS_CLOCK"
CDS_SEC"1"
SEC_TYPE"0402V"
SEC"1"
CDS_LOCATION"C4D24"
CDS_LIB"dev_discrete";
"B"
$PN"2"6;
"A"
$PN"1"19;
%"CAP_A"
"1","(-1800,3900)","0","dev_discrete","I19";
;
TOLERANCE"10%"
MATERIAL"X6S"
PART_NUMBER"D97712-004"
PACK_TYPE"0402V"
LOCATION"C4D23"
VALUE"1.0UF"
VOLTAGE"6.3V"
BOM_COST"SYS_CLOCK"
CDS_SEC"1"
SEC_TYPE"0402V"
SEC"1"
ROOM"DB1200ZL"
CDS_LOCATION"C4D23"
CDS_LIB"dev_discrete";
"B"
$PN"2"6;
"A"
$PN"1"19;
%"RES"
"1","(-2425,4125)","0","mstr_discrete","I21";
;
CDS_SEC"1"
VALUE"2.2"
TOLERANCE"1.0%"
PACK_TYPE"0603"
MATERIAL"CHIP"
LOCATION"R3D14"
WATTAGE"1/10W"
PART_NUMBER"G22026-127"
BOM_COST"SYS_CLOCK"
SEC_TYPE"0603"
SEC"1"
ROOM"DB1200ZL"
CDS_LIB"mstr_discrete"
CDS_LOCATION"R3D14";
"B"
$PN"2"19;
"A"
$PN"1"8;
%"GND"
"1","(-1550,3550)","0","mstr_symbols","I22";
;
SIZE"1B"
CDS_LIB"mstr_symbols"
BOM_COST"SYS_CLOCK"
ROOM"DB1200ZL"
VOLTAGE"0.0V"
BODY_TYPE"PLUMBING"
HDL_POWER"GND";
"A\NAC"6;
%"VCC_CORE"
"1","(3700,1300)","0","mstr_symbols","I23";
;
HDL_POWER"P3V3_DB1200"
CDS_LIB"mstr_symbols"
VOLTAGE"5";
"A"7;
%"VCC_CORE"
"1","(-2800,4250)","0","mstr_symbols","I24";
;
HDL_POWER"P3V3_DB1200"
CDS_LIB"mstr_symbols"
VOLTAGE"5";
"A"8;
%"VCC_CORE"
"1","(-825,3925)","0","mstr_symbols","I25";
;
HDL_POWER"P3V3_DB1200"
VOLTAGE"5"
CDS_LIB"mstr_symbols";
"A"9;
%"RES"
"1","(-2825,3400)","0","mstr_discrete","I26";
;
CDS_SEC"1"
PART_NUMBER"G22026-127"
LOCATION"R6P25"
VALUE"2.2"
PACK_TYPE"0603"
WATTAGE"1/10W"
TOLERANCE"1.0%"
MATERIAL"CHIP"
BOM_COST"SYS_CLOCK"
SEC_TYPE"0603"
SEC"1"
ROOM"DB1200ZL"
CDS_LIB"mstr_discrete"
CDS_LOCATION"R6P25";
"B"
$PN"2"38;
"A"
$PN"1"10;
%"VCC_CORE"
"1","(-3125,3550)","0","mstr_symbols","I27";
;
HDL_POWER"P3V3_DB1200"
CDS_LIB"mstr_symbols"
VOLTAGE"5";
"A"10;
%"CAP_A"
"1","(-2325,3225)","0","dev_discrete","I28";
;
VALUE"0.1UF"
VOLTAGE"16V"
TOLERANCE"10%"
MATERIAL"X7R"
PART_NUMBER"A36096-030"
LOCATION"C4D22"
PACK_TYPE"0402V"
BOM_COST"SYS_CLOCK"
ROOM"DB1200ZL"
CDS_LOCATION"C4D22"
CDS_SEC"1"
SEC_TYPE"0402V"
SEC"1"
CDS_LIB"dev_discrete";
"B"
$PN"2"11;
"A"
$PN"1"38;
%"GND"
"1","(-2325,2900)","0","mstr_symbols","I29";
;
BOM_COST"SYS_CLOCK"
ROOM"DB1200ZL"
VOLTAGE"0.0V"
CDS_LIB"mstr_symbols"
SIZE"1B"
BODY_TYPE"PLUMBING"
HDL_POWER"GND";
"A\NAC"11;
%"CAP_A"
"1","(-2575,3225)","0","dev_discrete","I30";
;
LOCATION"C4D27"
VALUE"1.0UF"
TOLERANCE"10%"
MATERIAL"X6S"
VOLTAGE"6.3V"
PART_NUMBER"D97712-004"
PACK_TYPE"0402V"
BOM_COST"SYS_CLOCK"
CDS_LOCATION"C4D27"
CDS_SEC"1"
SEC_TYPE"0402V"
SEC"1"
ROOM"DB1200ZL"
CDS_LIB"dev_discrete";
"B"
$PN"2"11;
"A"
$PN"1"38;
%"RES"
"2","(-2850,2850)","0","mstr_discrete","I37";
;
CDS_SEC"1"
PART_NUMBER"G21796-016"
LOCATION"R4D38"
VALUE"10.0K"
TOLERANCE"1%"
PACK_TYPE"0402"
MATERIAL"EMPTY"
WATTAGE"1/16W"
ROOM"DB1200ZL"
SEC"1"
SEC_TYPE"0402"
BOM_COST"SYS_CLOCK"
CDS_LOCATION"R4D38"
CDS_LIB"mstr_discrete";
"A"
$PN"1"12;
"B"
$PN"2"36;
%"RES"
"2","(-3225,2850)","0","mstr_discrete","I38";
;
CDS_SEC"1"
LOCATION"R4D35"
VALUE"10.0K"
TOLERANCE"1%"
WATTAGE"1/16W"
MATERIAL"EMPTY"
PACK_TYPE"0402"
PART_NUMBER"G21796-016"
CDS_LIB"mstr_discrete"
CDS_LOCATION"R4D35"
BOM_COST"SYS_CLOCK"
SEC_TYPE"0402"
SEC"1"
ROOM"DB1200ZL";
"A"
$PN"1"12;
"B"
$PN"2"35;
%"VCC_CORE"
"1","(-3225,3150)","0","mstr_symbols","I43";
;
HDL_POWER"P3V3_DB1200"
VOLTAGE"5"
CDS_LIB"mstr_symbols";
"A"12;
%"GND"
"1","(-2850,2125)","0","mstr_symbols","I44";
;
SIZE"1B"
CDS_LIB"mstr_symbols"
VOLTAGE"0.0V"
BOM_COST"SYS_CLOCK"
ROOM"DB1200ZL"
BODY_TYPE"PLUMBING"
HDL_POWER"GND";
"A\NAC"13;
%"RES"
"2","(-2675,1425)","0","mstr_discrete","I45";
;
CDS_SEC"1"
PACK_TYPE"0402"
PART_NUMBER"G21796-072"
MATERIAL"CHIP"
WATTAGE"1/16W"
TOLERANCE"1%"
VALUE"4.75K"
LOCATION"R4D40"
CDS_LIB"mstr_discrete"
ROOM"DB1200ZL"
CDS_LOCATION"R4D40"
SEC"1"
BOM_COST"SYS_CLOCK"
SEC_TYPE"0402";
"A"
$PN"1"14;
"B"
$PN"2"53;
%"RES"
"2","(-2675,1025)","0","mstr_discrete","I46";
;
CDS_SEC"1"
LOCATION"R6P23"
VALUE"4.75K"
TOLERANCE"1%"
WATTAGE"1/16W"
MATERIAL"EMPTY"
PART_NUMBER"G21796-072"
PACK_TYPE"0402"
ROOM"DB1200ZL"
SEC"1"
BOM_COST"SYS_CLOCK"
SEC_TYPE"0402"
CDS_LOCATION"R6P23"
CDS_LIB"mstr_discrete";
"A"
$PN"1"53;
"B"
$PN"2"15;
%"RES"
"2","(-2925,1025)","2","mstr_discrete","I47";
;
CDS_SEC"1"
LOCATION"R6P22"
VALUE"4.75K"
TOLERANCE"1%"
WATTAGE"1/16W"
MATERIAL"EMPTY"
PART_NUMBER"G21796-072"
PACK_TYPE"0402"
SEC_TYPE"0402"
BOM_COST"SYS_CLOCK"
SEC"1"
ROOM"DB1200ZL"
CDS_LIB"mstr_discrete"
CDS_LOCATION"R6P22";
"A"
$PN"1"52;
"B"
$PN"2"15;
%"VCC_CORE"
"1","(-2925,1800)","0","mstr_symbols","I49";
;
HDL_POWER"P3V3_DB1200"
VOLTAGE"5"
CDS_LIB"mstr_symbols";
"A"14;
%"GND"
"1","(-2675,700)","0","mstr_symbols","I50";
;
CDS_LIB"mstr_symbols"
SIZE"1B"
VOLTAGE"0.0V"
ROOM"DB1200ZL"
BOM_COST"SYS_CLOCK"
BODY_TYPE"PLUMBING"
HDL_POWER"GND";
"A\NAC"15;
%"RES"
"2","(-2925,1425)","2","mstr_discrete","I53";
;
CDS_SEC"1"
LOCATION"R4D41"
VALUE"4.75K"
TOLERANCE"1%"
WATTAGE"1/16W"
MATERIAL"CHIP"
PART_NUMBER"G21796-072"
PACK_TYPE"0402"
BOM_COST"SYS_CLOCK"
SEC_TYPE"0402"
SEC"1"
CDS_LOCATION"R4D41"
ROOM"DB1200ZL"
CDS_LIB"mstr_discrete";
"A"
$PN"1"14;
"B"
$PN"2"52;
%"GND"
"1","(1425,1725)","0","mstr_symbols","I6";
;
CDS_LIB"mstr_symbols"
SIZE"1B"
VOLTAGE"0.0V"
ROOM"DB1200ZL"
BOM_COST"SYS_CLOCK"
BODY_TYPE"PLUMBING"
HDL_POWER"GND";
"A\NAC"16;
%"CAP_A"
"1","(2275,900)","0","dev_discrete","I79";
;
PART_NUMBER"A36096-030"
VOLTAGE"16V"
MATERIAL"X7R"
TOLERANCE"10%"
PACK_TYPE"0402V"
LOCATION"C6P9"
VALUE"0.1UF"
CDS_SEC"1"
BOM_COST"SYS_CLOCK"
CDS_LOCATION"C6P9"
SEC"1"
ROOM"DB1200ZL"
SEC_TYPE"0402V"
CDS_LIB"dev_discrete";
"B"
$PN"2"5;
"A"
$PN"1"7;
%"FERRITE"
"1","(1700,1125)","0","mstr_discrete","I8";
;
CDS_SEC"1"
MATERIAL"FB"
PACK_TYPE"SMLF"
VALUE"600"
PART_NUMBER"656554-043"
LOCATION"FB6P1"
ROOM"DB1200ZL"
SEC"1"
SEC_TYPE"SMLF"
BOM_COST"SYS_CLOCK"
CDS_LOCATION"FB6P1"
CDS_LIB"mstr_discrete";
"A"
$PN"1"17;
"B"
$PN"2"7;
%"RES"
"2","(-3225,2475)","0","mstr_discrete","I80";
;
CDS_SEC"1"
LOCATION"R6P21"
VALUE"1.00K"
TOLERANCE"1%"
WATTAGE"1/16W"
MATERIAL"CHIP"
PACK_TYPE"0402"
PART_NUMBER"G21796-026"
SEC_TYPE"0402"
ROOM"DB1200ZL"
CDS_LOCATION"R6P21"
SEC"1"
BOM_COST"SYS_CLOCK"
CDS_LIB"mstr_discrete";
"A"
$PN"1"35;
"B"
$PN"2"13;
%"RES"
"2","(-2850,2475)","0","mstr_discrete","I81";
;
CDS_SEC"1"
LOCATION"R6P20"
VALUE"1.00K"
TOLERANCE"1%"
WATTAGE"1/16W"
MATERIAL"CHIP"
PACK_TYPE"0402"
PART_NUMBER"G21796-026"
SEC_TYPE"0402"
BOM_COST"SYS_CLOCK"
SEC"1"
CDS_LOCATION"R6P20"
ROOM"DB1200ZL"
CDS_LIB"mstr_discrete";
"A"
$PN"1"36;
"B"
$PN"2"13;
%"P3V3"
"1","(1475,1275)","0","mstr_symbols","I9";
;
CDS_LIB"mstr_symbols"
SIZE"1B"
VOLTAGE"3.3V"
BODY_TYPE"PLUMBING"
HDL_POWER"P3V3";
"G\NAC"17;
%"RES"
"2","(-125,1075)","2","mstr_discrete","I93";
;
CDS_SEC"1"
CDS_LOCATION"R4D69"
TOLERANCE"1%"
PACK_TYPE"0402"
MATERIAL"CHIP"
PART_NUMBER"G21796-072"
WATTAGE"1/16W"
VALUE"4.75K"
LOCATION"R4D69"
BOM_COST"SYS_CLOCK"
SIGNAL_MODEL"DEFAULT_RESISTOR_47000OHM_2_1"
SEC_TYPE"0402"
SEC"1"
ROOM"DB1200ZL"
CDS_LIB"mstr_discrete";
"A"
$PN"1"18;
"B"
$PN"2"21;
%"RES"
"2","(200,1075)","2","mstr_discrete","I94";
;
CDS_SEC"1"
CDS_LOCATION"R4D70"
VALUE"4.75K"
LOCATION"R4D70"
TOLERANCE"1%"
PART_NUMBER"G21796-072"
MATERIAL"CHIP"
WATTAGE"1/16W"
PACK_TYPE"0402"
SIGNAL_MODEL"DEFAULT_RESISTOR_47000OHM_2_1"
BOM_COST"SYS_CLOCK"
SEC_TYPE"0402"
SEC"1"
ROOM"DB1200ZL"
CDS_LIB"mstr_discrete";
"A"
$PN"1"18;
"B"
$PN"2"54;
%"P3V3"
"1","(-750,1375)","0","mstr_symbols","I95";
;
HDL_POWER"P3V3"
BODY_TYPE"PLUMBING"
VOLTAGE"3.3V"
CDS_LIB"mstr_symbols"
SIZE"1B";
"G\NAC"18;
END.
